FILE_TYPE = MACRO_DRAWING;
SET COLOR_WIRE YELLOW;
SET COLOR_PROP ORANGE;
SET COLOR_DOT WHITE;
SET COLOR_ARC YELLOW;
SET COLOR_BODY GREEN;
SET COLOR_NOTE PURPLE;
SET PROP_DISPLAY VALUE;
SET PAGE_NUMBER P133;
FORCEADD UNIVERSAL_POWER..1
(-3925 5225);
FORCEPROP 3 LASTPIN (-3925 5175) SIG_NAME P3V3_STBY\g
J 0
(-3915 5185);
DISPLAY 0.659574 (-3915 5185);
PAINT MONO (-3915 5185);
DISPLAY INVISIBLE (-3915 5185);
FORCEPROP 1 LAST HDL_POWER P3V3_STBY
J 1
(-3925 5275);
DISPLAY 0.489362 (-3925 5275);
PAINT GREEN (-3925 5275);
FORCEPROP 2 LAST CDS_LIB pure_quanta_power
J 0
(-3925 5225);
PAINT MONO (-3925 5225);
DISPLAY INVISIBLE (-3925 5225);
FORCEPROP 1 LAST PATH I18
J 0
(-3875 5250);
DISPLAY 0.872340 (-3875 5250);
PAINT AQUA (-3875 5250);
DISPLAY INVISIBLE (-3875 5250);
FORCEADD Q_RES..2
(-3925 5025);
FORCEPROP 1 LAST LOCATION R984
J 0
(-3880 5150);
DISPLAY 0.489362 (-3880 5150);
PAINT SKYBLUE (-3880 5150);
FORCEPROP 2 LAST $SEC 1
J 0
(-3875 5250);
DISPLAY 0.680851 (-3875 5250);
PAINT MONO (-3875 5250);
DISPLAY INVISIBLE (-3875 5250);
FORCEPROP 2 LAST CDS_SEC 1
J 0
(-3875 5250);
DISPLAY 1.021277 (-3875 5250);
DISPLAY INVISIBLE (-3875 5250);
FORCEPROP 1 LASTPIN (-3925 5125) $PN 1
J 0
(-3920 5087);
DISPLAY 0.489362 (-3920 5087);
FORCEPROP 1 LASTPIN (-3925 4925) $PN 2
J 0
(-3920 4935);
DISPLAY 0.489362 (-3920 4935);
FORCEPROP 1 LAST WATTAGE 1/16W
J 0
(-3885 5000);
DISPLAY 0.489362 (-3885 5000);
PAINT SKYBLUE (-3885 5000);
FORCEPROP 1 LAST MATERIAL CHIP
J 0
(-3885 4950);
DISPLAY 0.489362 (-3885 4950);
PAINT SKYBLUE (-3885 4950);
FORCEPROP 1 LAST TOLERANCE 1%
J 0
(-3880 5050);
DISPLAY 0.489362 (-3880 5050);
PAINT SKYBLUE (-3880 5050);
FORCEPROP 1 LAST VALUE 4.7K
J 0
(-3880 5100);
DISPLAY 0.489362 (-3880 5100);
PAINT SKYBLUE (-3880 5100);
FORCEPROP 1 LAST PART_NUMBER CS24702FB10
J 0
(-3885 4900);
DISPLAY 0.489362 (-3885 4900);
PAINT SKYBLUE (-3885 4900);
FORCEPROP 1 LAST PACK_TYPE 0402LF
J 0
(-3885 4850);
DISPLAY 0.489362 (-3885 4850);
PAINT SKYBLUE (-3885 4850);
FORCEPROP 2 LAST CDS_LIB pure_quanta
J 0
(-3925 5025);
PAINT MONO (-3925 5025);
DISPLAY INVISIBLE (-3925 5025);
FORCEPROP 1 LAST PATH I19
J 0
(-3875 5200);
DISPLAY 0.978723 (-3875 5200);
PAINT WHITE (-3875 5200);
DISPLAY INVISIBLE (-3875 5200);
FORCEADD UNIVERSAL_POWER..1
(-3925 4550);
FORCEPROP 3 LASTPIN (-3925 4500) SIG_NAME P3V3_STBY\g
J 0
(-3915 4510);
DISPLAY 0.659574 (-3915 4510);
PAINT MONO (-3915 4510);
DISPLAY INVISIBLE (-3915 4510);
FORCEPROP 1 LAST HDL_POWER P3V3_STBY
J 1
(-3925 4600);
DISPLAY 0.489362 (-3925 4600);
PAINT GREEN (-3925 4600);
FORCEPROP 2 LAST CDS_LIB pure_quanta_power
J 0
(-3925 4550);
PAINT MONO (-3925 4550);
DISPLAY INVISIBLE (-3925 4550);
FORCEPROP 1 LAST PATH I22
J 0
(-3875 4575);
DISPLAY 0.872340 (-3875 4575);
PAINT AQUA (-3875 4575);
DISPLAY INVISIBLE (-3875 4575);
FORCEADD Q_RES..2
(-3925 4350);
FORCEPROP 1 LAST LOCATION R985
J 0
(-3880 4475);
DISPLAY 0.489362 (-3880 4475);
PAINT SKYBLUE (-3880 4475);
FORCEPROP 2 LAST $SEC 1
J 0
(-3875 4575);
DISPLAY 0.680851 (-3875 4575);
PAINT MONO (-3875 4575);
DISPLAY INVISIBLE (-3875 4575);
FORCEPROP 2 LAST CDS_SEC 1
J 0
(-3875 4575);
DISPLAY 1.021277 (-3875 4575);
DISPLAY INVISIBLE (-3875 4575);
FORCEPROP 1 LASTPIN (-3925 4450) $PN 1
J 0
(-3920 4412);
DISPLAY 0.489362 (-3920 4412);
FORCEPROP 1 LASTPIN (-3925 4250) $PN 2
J 0
(-3920 4260);
DISPLAY 0.489362 (-3920 4260);
FORCEPROP 1 LAST WATTAGE 1/16W
J 0
(-3885 4325);
DISPLAY 0.489362 (-3885 4325);
PAINT SKYBLUE (-3885 4325);
FORCEPROP 1 LAST MATERIAL CHIP
J 0
(-3885 4275);
DISPLAY 0.489362 (-3885 4275);
PAINT SKYBLUE (-3885 4275);
FORCEPROP 1 LAST TOLERANCE 1%
J 0
(-3880 4375);
DISPLAY 0.489362 (-3880 4375);
PAINT SKYBLUE (-3880 4375);
FORCEPROP 1 LAST VALUE 4.7K
J 0
(-3880 4425);
DISPLAY 0.489362 (-3880 4425);
PAINT SKYBLUE (-3880 4425);
FORCEPROP 1 LAST PART_NUMBER CS24702FB10
J 0
(-3885 4225);
DISPLAY 0.489362 (-3885 4225);
PAINT SKYBLUE (-3885 4225);
FORCEPROP 1 LAST PACK_TYPE 0402LF
J 0
(-3885 4175);
DISPLAY 0.489362 (-3885 4175);
PAINT SKYBLUE (-3885 4175);
FORCEPROP 2 LAST CDS_LIB pure_quanta
J 0
(-3925 4350);
PAINT MONO (-3925 4350);
DISPLAY INVISIBLE (-3925 4350);
FORCEPROP 1 LAST PATH I23
J 0
(-3875 4525);
DISPLAY 0.978723 (-3875 4525);
PAINT WHITE (-3875 4525);
DISPLAY INVISIBLE (-3875 4525);
FORCEADD Q_DIODE..1
R 2
(-4325 4650);
FORCEPROP 1 LAST LOCATION D45
J 2
(-4250 4835);
DISPLAY 0.489362 (-4250 4835);
PAINT SKYBLUE (-4250 4835);
FORCEPROP 0 LAST $SEC 1
J 0
(-4250 4875);
DISPLAY 0.680851 (-4250 4875);
PAINT MONO (-4250 4875);
DISPLAY INVISIBLE (-4250 4875);
FORCEPROP 0 LAST CDS_SEC 1
J 0
(-4250 4875);
DISPLAY 1.021277 (-4250 4875);
DISPLAY INVISIBLE (-4250 4875);
FORCEPROP 0 LASTPIN (-4200 4650) $PN 1
J 0
(-4190 4660);
DISPLAY 0.489362 (-4190 4660);
PAINT MONO (-4190 4660);
FORCEPROP 0 LASTPIN (-4450 4650) $PN 2
J 2
(-4460 4660);
DISPLAY 0.489362 (-4460 4660);
PAINT MONO (-4460 4660);
FORCEPROP 1 LAST MATERIAL IC
J 2
(-4250 4725);
DISPLAY 0.489362 (-4250 4725);
PAINT SKYBLUE (-4250 4725);
FORCEPROP 2 LAST VALUE SDMK0340L-7-F
J 2
(-4250 4775);
DISPLAY 0.489362 (-4250 4775);
PAINT SKYBLUE (-4250 4775);
FORCEPROP 1 LAST PART_NUMBER BC000340033
J 2
(-4300 4725);
DISPLAY 0.489362 (-4300 4725);
PAINT SKYBLUE (-4300 4725);
FORCEPROP 2 LAST PACK_TYPE SMLF
J 2
(-4250 4800);
DISPLAY 0.489362 (-4250 4800);
PAINT SKYBLUE (-4250 4800);
FORCEPROP 2 LAST BOM_COST MISC.
J 0
(-4250 4875);
DISPLAY 0.680851 (-4250 4875);
DISPLAY INVISIBLE (-4250 4875);
FORCEPROP 1 LAST PIN_NAMES_ROTATE True
J 2
(-4250 4810);
DISPLAY 0.255319 (-4250 4810);
PAINT GREEN (-4250 4810);
DISPLAY INVISIBLE (-4250 4810);
FORCEPROP 1 LAST NEEDS_NO_SIZE TRUE
J 2
(-4325 4650);
DISPLAY 0.468085 (-4325 4650);
PAINT GREEN (-4325 4650);
DISPLAY INVISIBLE (-4325 4650);
FORCEPROP 2 LAST CDS_LIB pure_quanta
J 0
(-4325 4650);
DISPLAY INVISIBLE (-4325 4650);
FORCEPROP 1 LAST PATH I24
J 2
(-4425 4730);
DISPLAY 0.723404 (-4425 4730);
PAINT GREEN (-4425 4730);
DISPLAY INVISIBLE (-4425 4730);
FORCEADD Q_DIODE..1
R 2
(-4300 3975);
FORCEPROP 1 LAST LOCATION D53
J 2
(-4225 4175);
DISPLAY 0.489362 (-4225 4175);
PAINT SKYBLUE (-4225 4175);
FORCEPROP 0 LAST $SEC 1
J 0
(-4225 4200);
DISPLAY 0.680851 (-4225 4200);
PAINT MONO (-4225 4200);
DISPLAY INVISIBLE (-4225 4200);
FORCEPROP 0 LAST CDS_SEC 1
J 0
(-4225 4200);
DISPLAY 1.021277 (-4225 4200);
DISPLAY INVISIBLE (-4225 4200);
FORCEPROP 0 LASTPIN (-4175 3975) $PN 1
J 0
(-4165 3985);
DISPLAY 0.489362 (-4165 3985);
PAINT MONO (-4165 3985);
FORCEPROP 0 LASTPIN (-4425 3975) $PN 2
J 2
(-4435 3985);
DISPLAY 0.489362 (-4435 3985);
PAINT MONO (-4435 3985);
FORCEPROP 1 LAST MATERIAL IC
J 2
(-4225 4050);
DISPLAY 0.489362 (-4225 4050);
PAINT SKYBLUE (-4225 4050);
FORCEPROP 2 LAST VALUE SDMK0340L-7-F
J 2
(-4225 4100);
DISPLAY 0.489362 (-4225 4100);
PAINT SKYBLUE (-4225 4100);
FORCEPROP 1 LAST PART_NUMBER BC000340033
J 2
(-4275 4050);
DISPLAY 0.489362 (-4275 4050);
PAINT SKYBLUE (-4275 4050);
FORCEPROP 2 LAST PACK_TYPE SMLF
J 2
(-4225 4125);
DISPLAY 0.489362 (-4225 4125);
PAINT SKYBLUE (-4225 4125);
FORCEPROP 2 LAST CDS_LIB pure_quanta
J 0
(-4300 3975);
DISPLAY INVISIBLE (-4300 3975);
FORCEPROP 2 LAST BOM_COST MISC.
J 0
(-4225 4200);
DISPLAY 0.680851 (-4225 4200);
DISPLAY INVISIBLE (-4225 4200);
FORCEPROP 1 LAST PIN_NAMES_ROTATE True
J 2
(-4225 4135);
DISPLAY 0.255319 (-4225 4135);
PAINT GREEN (-4225 4135);
DISPLAY INVISIBLE (-4225 4135);
FORCEPROP 1 LAST NEEDS_NO_SIZE TRUE
J 2
(-4300 3975);
DISPLAY 0.468085 (-4300 3975);
PAINT GREEN (-4300 3975);
DISPLAY INVISIBLE (-4300 3975);
FORCEPROP 1 LAST PATH I26
J 2
(-4400 4055);
DISPLAY 0.723404 (-4400 4055);
PAINT GREEN (-4400 4055);
DISPLAY INVISIBLE (-4400 4055);
FORCEADD Q_DIODE..1
R 2
(-4275 3300);
FORCEPROP 1 LAST LOCATION D57
J 2
(-4200 3485);
DISPLAY 0.489362 (-4200 3485);
PAINT SKYBLUE (-4200 3485);
FORCEPROP 0 LAST $SEC 1
J 0
(-4200 3525);
DISPLAY 0.680851 (-4200 3525);
PAINT MONO (-4200 3525);
DISPLAY INVISIBLE (-4200 3525);
FORCEPROP 0 LAST CDS_SEC 1
J 0
(-4200 3525);
DISPLAY 1.021277 (-4200 3525);
DISPLAY INVISIBLE (-4200 3525);
FORCEPROP 0 LASTPIN (-4150 3300) $PN 1
J 0
(-4140 3310);
DISPLAY 0.489362 (-4140 3310);
PAINT MONO (-4140 3310);
FORCEPROP 0 LASTPIN (-4400 3300) $PN 2
J 2
(-4410 3310);
DISPLAY 0.489362 (-4410 3310);
PAINT MONO (-4410 3310);
FORCEPROP 1 LAST MATERIAL IC
J 2
(-4200 3375);
DISPLAY 0.489362 (-4200 3375);
PAINT SKYBLUE (-4200 3375);
FORCEPROP 2 LAST VALUE SDMK0340L-7-F
J 2
(-4200 3425);
DISPLAY 0.489362 (-4200 3425);
PAINT SKYBLUE (-4200 3425);
FORCEPROP 1 LAST PART_NUMBER BC000340033
J 2
(-4250 3375);
DISPLAY 0.489362 (-4250 3375);
PAINT SKYBLUE (-4250 3375);
FORCEPROP 2 LAST PACK_TYPE SMLF
J 2
(-4200 3450);
DISPLAY 0.489362 (-4200 3450);
PAINT SKYBLUE (-4200 3450);
FORCEPROP 2 LAST CDS_LIB pure_quanta
J 0
(-4275 3300);
DISPLAY INVISIBLE (-4275 3300);
FORCEPROP 1 LAST NEEDS_NO_SIZE TRUE
J 2
(-4275 3300);
DISPLAY 0.468085 (-4275 3300);
PAINT GREEN (-4275 3300);
DISPLAY INVISIBLE (-4275 3300);
FORCEPROP 1 LAST PIN_NAMES_ROTATE True
J 2
(-4200 3460);
DISPLAY 0.255319 (-4200 3460);
PAINT GREEN (-4200 3460);
DISPLAY INVISIBLE (-4200 3460);
FORCEPROP 2 LAST BOM_COST MISC.
J 0
(-4200 3525);
DISPLAY 0.680851 (-4200 3525);
DISPLAY INVISIBLE (-4200 3525);
FORCEPROP 1 LAST PATH I37
J 2
(-4375 3380);
DISPLAY 0.723404 (-4375 3380);
PAINT GREEN (-4375 3380);
DISPLAY INVISIBLE (-4375 3380);
FORCEADD Q_DIODE..1
R 2
(-4300 2575);
FORCEPROP 1 LAST LOCATION D55
J 2
(-4225 2760);
DISPLAY 0.489362 (-4225 2760);
PAINT SKYBLUE (-4225 2760);
FORCEPROP 0 LAST $SEC 1
J 0
(-4225 2800);
DISPLAY 0.680851 (-4225 2800);
PAINT MONO (-4225 2800);
DISPLAY INVISIBLE (-4225 2800);
FORCEPROP 0 LAST CDS_SEC 1
J 0
(-4225 2800);
DISPLAY 1.021277 (-4225 2800);
DISPLAY INVISIBLE (-4225 2800);
FORCEPROP 0 LASTPIN (-4175 2575) $PN 1
J 0
(-4165 2585);
DISPLAY 0.489362 (-4165 2585);
PAINT MONO (-4165 2585);
FORCEPROP 0 LASTPIN (-4425 2575) $PN 2
J 2
(-4435 2585);
DISPLAY 0.489362 (-4435 2585);
PAINT MONO (-4435 2585);
FORCEPROP 1 LAST MATERIAL IC
J 2
(-4225 2650);
DISPLAY 0.489362 (-4225 2650);
PAINT SKYBLUE (-4225 2650);
FORCEPROP 2 LAST VALUE SDMK0340L-7-F
J 2
(-4225 2700);
DISPLAY 0.489362 (-4225 2700);
PAINT SKYBLUE (-4225 2700);
FORCEPROP 1 LAST PART_NUMBER BC000340033
J 2
(-4275 2650);
DISPLAY 0.489362 (-4275 2650);
PAINT SKYBLUE (-4275 2650);
FORCEPROP 2 LAST PACK_TYPE SMLF
J 2
(-4225 2725);
DISPLAY 0.489362 (-4225 2725);
PAINT SKYBLUE (-4225 2725);
FORCEPROP 2 LAST BOM_COST MISC.
J 0
(-4225 2800);
DISPLAY 0.680851 (-4225 2800);
DISPLAY INVISIBLE (-4225 2800);
FORCEPROP 1 LAST PIN_NAMES_ROTATE True
J 2
(-4225 2735);
DISPLAY 0.255319 (-4225 2735);
PAINT GREEN (-4225 2735);
DISPLAY INVISIBLE (-4225 2735);
FORCEPROP 1 LAST NEEDS_NO_SIZE TRUE
J 2
(-4300 2575);
DISPLAY 0.468085 (-4300 2575);
PAINT GREEN (-4300 2575);
DISPLAY INVISIBLE (-4300 2575);
FORCEPROP 2 LAST CDS_LIB pure_quanta
J 0
(-4300 2575);
DISPLAY INVISIBLE (-4300 2575);
FORCEPROP 1 LAST PATH I39
J 2
(-4400 2655);
DISPLAY 0.723404 (-4400 2655);
PAINT GREEN (-4400 2655);
DISPLAY INVISIBLE (-4400 2655);
FORCEADD Q_DIODE..1
R 2
(-4325 1875);
FORCEPROP 1 LAST LOCATION D47
J 2
(-4250 2060);
DISPLAY 0.489362 (-4250 2060);
PAINT SKYBLUE (-4250 2060);
FORCEPROP 0 LAST $SEC 1
J 0
(-4250 2100);
DISPLAY 0.680851 (-4250 2100);
PAINT MONO (-4250 2100);
DISPLAY INVISIBLE (-4250 2100);
FORCEPROP 0 LAST CDS_SEC 1
J 0
(-4250 2100);
DISPLAY 1.021277 (-4250 2100);
DISPLAY INVISIBLE (-4250 2100);
FORCEPROP 0 LASTPIN (-4200 1875) $PN 1
J 0
(-4190 1885);
DISPLAY 0.489362 (-4190 1885);
PAINT MONO (-4190 1885);
FORCEPROP 0 LASTPIN (-4450 1875) $PN 2
J 2
(-4460 1885);
DISPLAY 0.489362 (-4460 1885);
PAINT MONO (-4460 1885);
FORCEPROP 1 LAST MATERIAL IC
J 2
(-4250 1950);
DISPLAY 0.489362 (-4250 1950);
PAINT SKYBLUE (-4250 1950);
FORCEPROP 2 LAST VALUE SDMK0340L-7-F
J 2
(-4250 2000);
DISPLAY 0.489362 (-4250 2000);
PAINT SKYBLUE (-4250 2000);
FORCEPROP 1 LAST PART_NUMBER BC000340033
J 2
(-4300 1950);
DISPLAY 0.489362 (-4300 1950);
PAINT SKYBLUE (-4300 1950);
FORCEPROP 2 LAST PACK_TYPE SMLF
J 2
(-4250 2025);
DISPLAY 0.489362 (-4250 2025);
PAINT SKYBLUE (-4250 2025);
FORCEPROP 2 LAST BOM_COST MISC.
J 0
(-4250 2100);
DISPLAY 0.680851 (-4250 2100);
DISPLAY INVISIBLE (-4250 2100);
FORCEPROP 1 LAST PIN_NAMES_ROTATE True
J 2
(-4250 2035);
DISPLAY 0.255319 (-4250 2035);
PAINT GREEN (-4250 2035);
DISPLAY INVISIBLE (-4250 2035);
FORCEPROP 1 LAST NEEDS_NO_SIZE TRUE
J 2
(-4325 1875);
DISPLAY 0.468085 (-4325 1875);
PAINT GREEN (-4325 1875);
DISPLAY INVISIBLE (-4325 1875);
FORCEPROP 2 LAST CDS_LIB pure_quanta
J 0
(-4325 1875);
DISPLAY INVISIBLE (-4325 1875);
FORCEPROP 1 LAST PATH I40
J 2
(-4425 1955);
DISPLAY 0.723404 (-4425 1955);
PAINT GREEN (-4425 1955);
DISPLAY INVISIBLE (-4425 1955);
FORCEADD Q_DIODE..1
R 2
(-4325 1150);
FORCEPROP 1 LAST LOCATION D48
J 2
(-4250 1335);
DISPLAY 0.489362 (-4250 1335);
PAINT SKYBLUE (-4250 1335);
FORCEPROP 0 LAST $SEC 1
J 0
(-4250 1375);
DISPLAY 0.680851 (-4250 1375);
PAINT MONO (-4250 1375);
DISPLAY INVISIBLE (-4250 1375);
FORCEPROP 0 LAST CDS_SEC 1
J 0
(-4250 1375);
DISPLAY 1.021277 (-4250 1375);
DISPLAY INVISIBLE (-4250 1375);
FORCEPROP 0 LASTPIN (-4200 1150) $PN 1
J 0
(-4190 1160);
DISPLAY 0.489362 (-4190 1160);
PAINT MONO (-4190 1160);
FORCEPROP 0 LASTPIN (-4450 1150) $PN 2
J 2
(-4460 1160);
DISPLAY 0.489362 (-4460 1160);
PAINT MONO (-4460 1160);
FORCEPROP 1 LAST MATERIAL IC
J 2
(-4250 1225);
DISPLAY 0.489362 (-4250 1225);
PAINT SKYBLUE (-4250 1225);
FORCEPROP 2 LAST VALUE SDMK0340L-7-F
J 2
(-4250 1275);
DISPLAY 0.489362 (-4250 1275);
PAINT SKYBLUE (-4250 1275);
FORCEPROP 1 LAST PART_NUMBER BC000340033
J 2
(-4300 1225);
DISPLAY 0.489362 (-4300 1225);
PAINT SKYBLUE (-4300 1225);
FORCEPROP 2 LAST PACK_TYPE SMLF
J 2
(-4250 1300);
DISPLAY 0.489362 (-4250 1300);
PAINT SKYBLUE (-4250 1300);
FORCEPROP 2 LAST BOM_COST MISC.
J 0
(-4250 1375);
DISPLAY 0.680851 (-4250 1375);
DISPLAY INVISIBLE (-4250 1375);
FORCEPROP 1 LAST PIN_NAMES_ROTATE True
J 2
(-4250 1310);
DISPLAY 0.255319 (-4250 1310);
PAINT GREEN (-4250 1310);
DISPLAY INVISIBLE (-4250 1310);
FORCEPROP 1 LAST NEEDS_NO_SIZE TRUE
J 2
(-4325 1150);
DISPLAY 0.468085 (-4325 1150);
PAINT GREEN (-4325 1150);
DISPLAY INVISIBLE (-4325 1150);
FORCEPROP 2 LAST CDS_LIB pure_quanta
J 0
(-4325 1150);
DISPLAY INVISIBLE (-4325 1150);
FORCEPROP 1 LAST PATH I55
J 2
(-4425 1230);
DISPLAY 0.723404 (-4425 1230);
PAINT GREEN (-4425 1230);
DISPLAY INVISIBLE (-4425 1230);
FORCEADD UNIVERSAL_GND..1
R 2
(-7325 4750);
FORCEPROP 3 LASTPIN (-7325 4800) SIG_NAME GND\g
J 0
(-7315 4810);
DISPLAY 0.659574 (-7315 4810);
PAINT MONO (-7315 4810);
DISPLAY INVISIBLE (-7315 4810);
FORCEPROP 2 LAST CDS_LIB pure_quanta_power
J 0
(-7325 4750);
DISPLAY INVISIBLE (-7325 4750);
FORCEPROP 1 LAST PATH I67
J 2
(-7400 4750);
DISPLAY 0.872340 (-7400 4750);
PAINT AQUA (-7400 4750);
DISPLAY INVISIBLE (-7400 4750);
FORCEPROP 1 LAST HDL_POWER GND
J 1
(-7350 4675);
DISPLAY 0.872340 (-7350 4675);
PAINT GREEN (-7350 4675);
DISPLAY INVISIBLE (-7350 4675);
FORCEADD SN74LVC1G07DBVR..1
(-6975 4650);
FORCEPROP 1 LAST LOCATION U81
J 0
(-7100 4905);
DISPLAY 0.489362 (-7100 4905);
PAINT SKYBLUE (-7100 4905);
FORCEPROP 0 LAST $SEC 1
J 0
(-7100 5100);
DISPLAY 0.680851 (-7100 5100);
PAINT MONO (-7100 5100);
DISPLAY INVISIBLE (-7100 5100);
FORCEPROP 0 LAST CDS_SEC 1
J 0
(-7100 5100);
DISPLAY 0.680851 (-7100 5100);
DISPLAY INVISIBLE (-7100 5100);
FORCEPROP 0 LASTPIN (-7150 4650) $PN 2
J 2
(-7160 4660);
DISPLAY 0.489362 (-7160 4660);
PAINT MONO (-7160 4660);
FORCEPROP 0 LASTPIN (-7150 4550) $PN 3
J 2
(-7160 4560);
DISPLAY 0.489362 (-7160 4560);
PAINT MONO (-7160 4560);
FORCEPROP 0 LASTPIN (-6800 4550) $PN 1
J 0
(-6790 4560);
DISPLAY 0.489362 (-6790 4560);
PAINT MONO (-6790 4560);
FORCEPROP 0 LASTPIN (-7150 4750) $PN 5
J 2
(-7160 4760);
DISPLAY 0.489362 (-7160 4760);
PAINT MONO (-7160 4760);
FORCEPROP 0 LASTPIN (-6800 4650) $PN 4
J 0
(-6790 4660);
DISPLAY 0.489362 (-6790 4660);
PAINT MONO (-6790 4660);
FORCEPROP 2 LAST PART_TYPE SMLF
J 0
(-7100 5050);
DISPLAY 0.680851 (-7100 5050);
FORCEPROP 1 LAST MATERIAL IC
J 0
(-7100 4810);
DISPLAY 0.489362 (-7100 4810);
PAINT SKYBLUE (-7100 4810);
FORCEPROP 2 LAST VALUE SN74LVC1G07DBVR
J 0
(-7100 5000);
DISPLAY 0.489362 (-7100 5000);
PAINT SKYBLUE (-7100 5000);
FORCEPROP 1 LAST PART_NUMBER AL1G0007024
J 0
(-7100 4860);
DISPLAY 0.489362 (-7100 4860);
PAINT SKYBLUE (-7100 4860);
FORCEPROP 2 LAST CDS_LIB pure_quanta
J 0
(-6975 4650);
DISPLAY INVISIBLE (-6975 4650);
FORCEPROP 1 LAST NEEDS_NO_SIZE TRUE
J 0
(-6975 4650);
DISPLAY 0.468085 (-6975 4650);
PAINT GREEN (-6975 4650);
DISPLAY INVISIBLE (-6975 4650);
FORCEPROP 1 LAST PATH I68
J 0
(-6875 4805);
DISPLAY 0.723404 (-6875 4805);
PAINT GREEN (-6875 4805);
DISPLAY INVISIBLE (-6875 4805);
FORCEPROP 0 LAST PACK_TYPE SMLF
J 0
(-7100 5100);
DISPLAY 0.680851 (-7100 5100);
PAINT SKYBLUE (-7100 5100);
DISPLAY INVISIBLE (-7100 5100);
FORCEADD Q_CAP..1
R 2
(-7325 4950);
FORCEPROP 1 LAST LOCATION C550
J 2
(-7375 5100);
DISPLAY 0.489362 (-7375 5100);
PAINT SKYBLUE (-7375 5100);
FORCEPROP 0 LAST $SEC 1
J 0
(-7375 5150);
DISPLAY 0.680851 (-7375 5150);
PAINT MONO (-7375 5150);
DISPLAY INVISIBLE (-7375 5150);
FORCEPROP 0 LAST CDS_SEC 1
J 0
(-7375 5150);
DISPLAY 0.680851 (-7375 5150);
DISPLAY INVISIBLE (-7375 5150);
FORCEPROP 1 LASTPIN (-7325 5050) $PN 1
J 2
(-7335 5030);
DISPLAY 0.489362 (-7335 5030);
PAINT MONO (-7335 5030);
FORCEPROP 1 LASTPIN (-7325 4850) $PN 2
J 2
(-7335 4830);
DISPLAY 0.489362 (-7335 4830);
PAINT MONO (-7335 4830);
FORCEPROP 1 LAST MATERIAL X7R
J 2
(-7375 4900);
DISPLAY 0.489362 (-7375 4900);
PAINT SKYBLUE (-7375 4900);
FORCEPROP 1 LAST TOLERANCE 10%
J 2
(-7375 4950);
DISPLAY 0.489362 (-7375 4950);
PAINT SKYBLUE (-7375 4950);
FORCEPROP 1 LAST VALUE 0.1UF
J 2
(-7375 5050);
DISPLAY 0.489362 (-7375 5050);
PAINT SKYBLUE (-7375 5050);
FORCEPROP 1 LAST PART_NUMBER CH4104K1B00
J 2
(-7375 4800);
DISPLAY 0.489362 (-7375 4800);
PAINT SKYBLUE (-7375 4800);
FORCEPROP 1 LAST VOLTAGE 25V
J 2
(-7375 5000);
DISPLAY 0.489362 (-7375 5000);
PAINT SKYBLUE (-7375 5000);
FORCEPROP 1 LAST PACK_TYPE 0402
J 2
(-7375 4850);
DISPLAY 0.489362 (-7375 4850);
PAINT SKYBLUE (-7375 4850);
FORCEPROP 2 LAST CDS_LIB pure_quanta
J 0
(-7325 4950);
DISPLAY INVISIBLE (-7325 4950);
FORCEPROP 1 LAST PATH I69
J 2
(-7375 5100);
DISPLAY 0.978723 (-7375 5100);
PAINT WHITE (-7375 5100);
DISPLAY INVISIBLE (-7375 5100);
FORCEADD UNIVERSAL_POWER..1
(-7250 5225);
FORCEPROP 3 LASTPIN (-7250 5175) SIG_NAME P3V3_STBY\g
J 0
(-7240 5185);
DISPLAY 0.659574 (-7240 5185);
PAINT MONO (-7240 5185);
DISPLAY INVISIBLE (-7240 5185);
FORCEPROP 1 LAST HDL_POWER P3V3_STBY
J 1
(-7250 5275);
DISPLAY 0.489362 (-7250 5275);
PAINT GREEN (-7250 5275);
FORCEPROP 2 LAST CDS_LIB pure_quanta_power
J 0
(-7250 5225);
DISPLAY INVISIBLE (-7250 5225);
FORCEPROP 2 LAST BOM_COST OCP3.0 
J 0
(-7250 5325);
DISPLAY 0.680851 (-7250 5325);
DISPLAY INVISIBLE (-7250 5325);
FORCEPROP 1 LAST PATH I70
J 0
(-7200 5250);
DISPLAY 0.872340 (-7200 5250);
PAINT AQUA (-7200 5250);
DISPLAY INVISIBLE (-7200 5250);
FORCEADD Q_RES..1
(-5875 4650);
FORCEPROP 1 LAST LOCATION R1324
J 0
(-6100 4650);
DISPLAY 0.489362 (-6100 4650);
PAINT SKYBLUE (-6100 4650);
FORCEPROP 0 LAST $SEC 1
J 0
(-5925 4750);
DISPLAY 0.680851 (-5925 4750);
PAINT MONO (-5925 4750);
DISPLAY INVISIBLE (-5925 4750);
FORCEPROP 0 LAST CDS_SEC 1
J 0
(-5925 4750);
DISPLAY 0.680851 (-5925 4750);
DISPLAY INVISIBLE (-5925 4750);
FORCEPROP 1 LASTPIN (-5975 4650) $PN 1
J 0
(-5963 4662);
DISPLAY 0.489362 (-5963 4662);
PAINT MONO (-5963 4662);
FORCEPROP 1 LASTPIN (-5775 4650) $PN 2
J 0
(-5813 4662);
DISPLAY 0.489362 (-5813 4662);
PAINT MONO (-5813 4662);
FORCEPROP 1 LAST VALUE 0
J 2
(-5725 4650);
DISPLAY 0.489362 (-5725 4650);
PAINT SKYBLUE (-5725 4650);
FORCEPROP 2 LAST BOM_COST OCP3.0 
J 0
(-5800 4750);
DISPLAY 0.680851 (-5800 4750);
DISPLAY INVISIBLE (-5800 4750);
FORCEPROP 2 LAST CDS_LIB pure_quanta
J 0
(-5875 4650);
DISPLAY INVISIBLE (-5875 4650);
FORCEPROP 1 LAST PATH I71
J 0
(-5925 4800);
DISPLAY 0.978723 (-5925 4800);
PAINT WHITE (-5925 4800);
DISPLAY INVISIBLE (-5925 4800);
FORCEPROP 1 LAST WATTAGE 1/16W
J 2
(-5900 4550);
DISPLAY 0.489362 (-5900 4550);
PAINT SKYBLUE (-5900 4550);
DISPLAY INVISIBLE (-5900 4550);
FORCEPROP 1 LAST MATERIAL CHIP
J 0
(-5725 4650);
DISPLAY 0.489362 (-5725 4650);
PAINT SKYBLUE (-5725 4650);
DISPLAY INVISIBLE (-5725 4650);
FORCEPROP 1 LAST TOLERANCE 5%
J 0
(-5875 4600);
DISPLAY 0.489362 (-5875 4600);
PAINT SKYBLUE (-5875 4600);
DISPLAY INVISIBLE (-5875 4600);
FORCEPROP 1 LAST PART_NUMBER CS00002JB38
J 0
(-5800 4700);
DISPLAY 0.489362 (-5800 4700);
PAINT SKYBLUE (-5800 4700);
DISPLAY INVISIBLE (-5800 4700);
FORCEPROP 1 LAST PACK_TYPE 0402LF
J 0
(-5800 4600);
DISPLAY 0.489362 (-5800 4600);
PAINT SKYBLUE (-5800 4600);
DISPLAY INVISIBLE (-5800 4600);
FORCEADD UNIVERSAL_GND..1
R 2
(-7225 4425);
FORCEPROP 3 LASTPIN (-7225 4475) SIG_NAME GND\g
J 0
(-7215 4485);
DISPLAY 0.659574 (-7215 4485);
PAINT MONO (-7215 4485);
DISPLAY INVISIBLE (-7215 4485);
FORCEPROP 2 LAST CDS_LIB pure_quanta_power
J 0
(-7225 4425);
DISPLAY INVISIBLE (-7225 4425);
FORCEPROP 1 LAST PATH I73
J 2
(-7300 4425);
DISPLAY 0.872340 (-7300 4425);
PAINT AQUA (-7300 4425);
DISPLAY INVISIBLE (-7300 4425);
FORCEPROP 1 LAST HDL_POWER GND
J 1
(-7250 4350);
DISPLAY 0.872340 (-7250 4350);
PAINT GREEN (-7250 4350);
DISPLAY INVISIBLE (-7250 4350);
FORCEADD OFFPAGE..1
(-8100 4650);
FORCEPROP 2 LAST $XR1 82 
J 0
(-8411 4650);
DISPLAY 0.638298 (-8411 4650);
PAINT MONO (-8411 4650);
FORCEPROP 2 LAST $XR0 79 
J 0
(-8321 4650);
DISPLAY 0.638298 (-8321 4650);
PAINT MONO (-8321 4650);
FORCEPROP 2 LAST CDS_LIB mstr_standard
J 0
(-8100 4650);
DISPLAY 0.659574 (-8100 4650);
DISPLAY INVISIBLE (-8100 4650);
FORCEPROP 1 LAST OFFPAGE TRUE
J 0
(-7775 4525);
DISPLAY 0.702128 (-7775 4525);
PAINT GREEN (-7775 4525);
DISPLAY INVISIBLE (-7775 4525);
FORCEPROP 1 LAST COMMENT_BODY TRUE
J 0
(-7975 4550);
DISPLAY 0.702128 (-7975 4550);
PAINT GREEN (-7975 4550);
DISPLAY INVISIBLE (-7975 4550);
FORCEPROP 2 LAST PATH I74
J 0
(-8350 4700);
DISPLAY 0.680851 (-8350 4700);
DISPLAY INVISIBLE (-8350 4700);
FORCEADD UNIVERSAL_POWER..1
(-4725 5225);
FORCEPROP 3 LASTPIN (-4725 5175) SIG_NAME P3V3_STBY\g
J 0
(-4715 5185);
DISPLAY 0.659574 (-4715 5185);
PAINT MONO (-4715 5185);
DISPLAY INVISIBLE (-4715 5185);
FORCEPROP 1 LAST HDL_POWER P3V3_STBY
J 1
(-4725 5275);
DISPLAY 0.489362 (-4725 5275);
PAINT GREEN (-4725 5275);
FORCEPROP 2 LAST CDS_LIB pure_quanta_power
J 0
(-4725 5225);
DISPLAY INVISIBLE (-4725 5225);
FORCEPROP 1 LAST PATH I75
J 0
(-4675 5250);
DISPLAY 0.872340 (-4675 5250);
PAINT AQUA (-4675 5250);
DISPLAY INVISIBLE (-4675 5250);
FORCEADD Q_RES..2
(-4725 5025);
FORCEPROP 1 LAST LOCATION R1325
J 0
(-4680 5150);
DISPLAY 0.489362 (-4680 5150);
PAINT SKYBLUE (-4680 5150);
FORCEPROP 0 LAST $SEC 1
J 0
(-4675 5200);
DISPLAY 0.680851 (-4675 5200);
PAINT MONO (-4675 5200);
DISPLAY INVISIBLE (-4675 5200);
FORCEPROP 0 LAST CDS_SEC 1
J 0
(-4675 5200);
DISPLAY 0.680851 (-4675 5200);
DISPLAY INVISIBLE (-4675 5200);
FORCEPROP 1 LASTPIN (-4725 5125) $PN 1
J 0
(-4720 5087);
DISPLAY 0.489362 (-4720 5087);
PAINT MONO (-4720 5087);
FORCEPROP 1 LASTPIN (-4725 4925) $PN 2
J 0
(-4720 4935);
DISPLAY 0.489362 (-4720 4935);
PAINT MONO (-4720 4935);
FORCEPROP 1 LAST WATTAGE 1/16W
J 0
(-4685 5000);
DISPLAY 0.489362 (-4685 5000);
PAINT SKYBLUE (-4685 5000);
FORCEPROP 1 LAST MATERIAL CHIP
J 0
(-4685 4950);
DISPLAY 0.489362 (-4685 4950);
PAINT SKYBLUE (-4685 4950);
FORCEPROP 1 LAST TOLERANCE 1%
J 0
(-4680 5050);
DISPLAY 0.489362 (-4680 5050);
PAINT SKYBLUE (-4680 5050);
FORCEPROP 1 LAST VALUE 4.7K
J 0
(-4680 5100);
DISPLAY 0.489362 (-4680 5100);
PAINT SKYBLUE (-4680 5100);
FORCEPROP 1 LAST PART_NUMBER CS24702FB10
J 0
(-4685 4900);
DISPLAY 0.489362 (-4685 4900);
PAINT SKYBLUE (-4685 4900);
FORCEPROP 1 LAST PACK_TYPE 0402LF
J 0
(-4685 4850);
DISPLAY 0.489362 (-4685 4850);
PAINT SKYBLUE (-4685 4850);
FORCEPROP 2 LAST CDS_LIB pure_quanta
J 0
(-4725 5025);
DISPLAY INVISIBLE (-4725 5025);
FORCEPROP 1 LAST PATH I76
J 0
(-4675 5200);
DISPLAY 0.978723 (-4675 5200);
PAINT WHITE (-4675 5200);
DISPLAY INVISIBLE (-4675 5200);
FORCEADD Q_RES..2
(-3900 3675);
FORCEPROP 1 LAST LOCATION R1326
J 0
(-3855 3800);
DISPLAY 0.489362 (-3855 3800);
PAINT SKYBLUE (-3855 3800);
FORCEPROP 0 LAST $SEC 1
J 0
(-3850 3850);
DISPLAY 0.680851 (-3850 3850);
PAINT MONO (-3850 3850);
DISPLAY INVISIBLE (-3850 3850);
FORCEPROP 0 LAST CDS_SEC 1
J 0
(-3850 3850);
DISPLAY 0.680851 (-3850 3850);
DISPLAY INVISIBLE (-3850 3850);
FORCEPROP 1 LASTPIN (-3900 3775) $PN 1
J 0
(-3895 3737);
DISPLAY 0.489362 (-3895 3737);
PAINT MONO (-3895 3737);
FORCEPROP 1 LASTPIN (-3900 3575) $PN 2
J 0
(-3895 3585);
DISPLAY 0.489362 (-3895 3585);
PAINT MONO (-3895 3585);
FORCEPROP 1 LAST WATTAGE 1/16W
J 0
(-3860 3650);
DISPLAY 0.489362 (-3860 3650);
PAINT SKYBLUE (-3860 3650);
FORCEPROP 1 LAST MATERIAL CHIP
J 0
(-3860 3600);
DISPLAY 0.489362 (-3860 3600);
PAINT SKYBLUE (-3860 3600);
FORCEPROP 1 LAST TOLERANCE 1%
J 0
(-3855 3700);
DISPLAY 0.489362 (-3855 3700);
PAINT SKYBLUE (-3855 3700);
FORCEPROP 1 LAST VALUE 4.7K
J 0
(-3855 3750);
DISPLAY 0.489362 (-3855 3750);
PAINT SKYBLUE (-3855 3750);
FORCEPROP 1 LAST PART_NUMBER CS24702FB10
J 0
(-3860 3550);
DISPLAY 0.489362 (-3860 3550);
PAINT SKYBLUE (-3860 3550);
FORCEPROP 1 LAST PACK_TYPE 0402LF
J 0
(-3860 3500);
DISPLAY 0.489362 (-3860 3500);
PAINT SKYBLUE (-3860 3500);
FORCEPROP 2 LAST CDS_LIB pure_quanta
J 0
(-3900 3675);
DISPLAY INVISIBLE (-3900 3675);
FORCEPROP 1 LAST PATH I77
J 0
(-3850 3850);
DISPLAY 0.978723 (-3850 3850);
PAINT WHITE (-3850 3850);
DISPLAY INVISIBLE (-3850 3850);
FORCEADD UNIVERSAL_POWER..1
(-3900 3875);
FORCEPROP 3 LASTPIN (-3900 3825) SIG_NAME P3V3_STBY\g
J 0
(-3890 3835);
DISPLAY 0.659574 (-3890 3835);
PAINT MONO (-3890 3835);
DISPLAY INVISIBLE (-3890 3835);
FORCEPROP 1 LAST HDL_POWER P3V3_STBY
J 1
(-3900 3925);
DISPLAY 0.489362 (-3900 3925);
PAINT GREEN (-3900 3925);
FORCEPROP 2 LAST CDS_LIB pure_quanta_power
J 0
(-3900 3875);
DISPLAY INVISIBLE (-3900 3875);
FORCEPROP 1 LAST PATH I78
J 0
(-3850 3900);
DISPLAY 0.872340 (-3850 3900);
PAINT AQUA (-3850 3900);
DISPLAY INVISIBLE (-3850 3900);
FORCEADD Q_RES..2
(-3875 2950);
FORCEPROP 1 LAST LOCATION R1327
J 0
(-3830 3075);
DISPLAY 0.489362 (-3830 3075);
PAINT SKYBLUE (-3830 3075);
FORCEPROP 0 LAST $SEC 1
J 0
(-3825 3125);
DISPLAY 0.680851 (-3825 3125);
PAINT MONO (-3825 3125);
DISPLAY INVISIBLE (-3825 3125);
FORCEPROP 0 LAST CDS_SEC 1
J 0
(-3825 3125);
DISPLAY 0.680851 (-3825 3125);
DISPLAY INVISIBLE (-3825 3125);
FORCEPROP 1 LASTPIN (-3875 3050) $PN 1
J 0
(-3870 3012);
DISPLAY 0.489362 (-3870 3012);
PAINT MONO (-3870 3012);
FORCEPROP 1 LASTPIN (-3875 2850) $PN 2
J 0
(-3870 2860);
DISPLAY 0.489362 (-3870 2860);
PAINT MONO (-3870 2860);
FORCEPROP 1 LAST WATTAGE 1/16W
J 0
(-3835 2925);
DISPLAY 0.489362 (-3835 2925);
PAINT SKYBLUE (-3835 2925);
FORCEPROP 1 LAST MATERIAL CHIP
J 0
(-3835 2875);
DISPLAY 0.489362 (-3835 2875);
PAINT SKYBLUE (-3835 2875);
FORCEPROP 1 LAST TOLERANCE 1%
J 0
(-3830 2975);
DISPLAY 0.489362 (-3830 2975);
PAINT SKYBLUE (-3830 2975);
FORCEPROP 1 LAST VALUE 4.7K
J 0
(-3830 3025);
DISPLAY 0.489362 (-3830 3025);
PAINT SKYBLUE (-3830 3025);
FORCEPROP 1 LAST PART_NUMBER CS24702FB10
J 0
(-3835 2825);
DISPLAY 0.489362 (-3835 2825);
PAINT SKYBLUE (-3835 2825);
FORCEPROP 1 LAST PACK_TYPE 0402LF
J 0
(-3835 2775);
DISPLAY 0.489362 (-3835 2775);
PAINT SKYBLUE (-3835 2775);
FORCEPROP 2 LAST CDS_LIB pure_quanta
J 0
(-3875 2950);
DISPLAY INVISIBLE (-3875 2950);
FORCEPROP 1 LAST PATH I79
J 0
(-3825 3125);
DISPLAY 0.978723 (-3825 3125);
PAINT WHITE (-3825 3125);
DISPLAY INVISIBLE (-3825 3125);
FORCEADD UNIVERSAL_POWER..1
(-3875 3150);
FORCEPROP 3 LASTPIN (-3875 3100) SIG_NAME P3V3_STBY\g
J 0
(-3865 3110);
DISPLAY 0.659574 (-3865 3110);
PAINT MONO (-3865 3110);
DISPLAY INVISIBLE (-3865 3110);
FORCEPROP 1 LAST HDL_POWER P3V3_STBY
J 1
(-3875 3200);
DISPLAY 0.489362 (-3875 3200);
PAINT GREEN (-3875 3200);
FORCEPROP 2 LAST CDS_LIB pure_quanta_power
J 0
(-3875 3150);
DISPLAY INVISIBLE (-3875 3150);
FORCEPROP 1 LAST PATH I80
J 0
(-3825 3175);
DISPLAY 0.872340 (-3825 3175);
PAINT AQUA (-3825 3175);
DISPLAY INVISIBLE (-3825 3175);
FORCEADD Q_RES..2
(-3875 2250);
FORCEPROP 1 LAST LOCATION R1328
J 0
(-3830 2375);
DISPLAY 0.489362 (-3830 2375);
PAINT SKYBLUE (-3830 2375);
FORCEPROP 0 LAST $SEC 1
J 0
(-3825 2425);
DISPLAY 0.680851 (-3825 2425);
PAINT MONO (-3825 2425);
DISPLAY INVISIBLE (-3825 2425);
FORCEPROP 0 LAST CDS_SEC 1
J 0
(-3825 2425);
DISPLAY 0.680851 (-3825 2425);
DISPLAY INVISIBLE (-3825 2425);
FORCEPROP 1 LASTPIN (-3875 2350) $PN 1
J 0
(-3870 2312);
DISPLAY 0.489362 (-3870 2312);
PAINT MONO (-3870 2312);
FORCEPROP 1 LASTPIN (-3875 2150) $PN 2
J 0
(-3870 2160);
DISPLAY 0.489362 (-3870 2160);
PAINT MONO (-3870 2160);
FORCEPROP 1 LAST WATTAGE 1/16W
J 0
(-3835 2225);
DISPLAY 0.489362 (-3835 2225);
PAINT SKYBLUE (-3835 2225);
FORCEPROP 1 LAST MATERIAL CHIP
J 0
(-3835 2175);
DISPLAY 0.489362 (-3835 2175);
PAINT SKYBLUE (-3835 2175);
FORCEPROP 1 LAST TOLERANCE 1%
J 0
(-3830 2275);
DISPLAY 0.489362 (-3830 2275);
PAINT SKYBLUE (-3830 2275);
FORCEPROP 1 LAST VALUE 4.7K
J 0
(-3830 2325);
DISPLAY 0.489362 (-3830 2325);
PAINT SKYBLUE (-3830 2325);
FORCEPROP 1 LAST PART_NUMBER CS24702FB10
J 0
(-3835 2125);
DISPLAY 0.489362 (-3835 2125);
PAINT SKYBLUE (-3835 2125);
FORCEPROP 1 LAST PACK_TYPE 0402LF
J 0
(-3835 2075);
DISPLAY 0.489362 (-3835 2075);
PAINT SKYBLUE (-3835 2075);
FORCEPROP 2 LAST CDS_LIB pure_quanta
J 0
(-3875 2250);
DISPLAY INVISIBLE (-3875 2250);
FORCEPROP 1 LAST PATH I81
J 0
(-3825 2425);
DISPLAY 0.978723 (-3825 2425);
PAINT WHITE (-3825 2425);
DISPLAY INVISIBLE (-3825 2425);
FORCEADD UNIVERSAL_POWER..1
(-3875 2450);
FORCEPROP 3 LASTPIN (-3875 2400) SIG_NAME P3V3_STBY\g
J 0
(-3865 2410);
DISPLAY 0.659574 (-3865 2410);
PAINT MONO (-3865 2410);
DISPLAY INVISIBLE (-3865 2410);
FORCEPROP 1 LAST HDL_POWER P3V3_STBY
J 1
(-3875 2500);
DISPLAY 0.489362 (-3875 2500);
PAINT GREEN (-3875 2500);
FORCEPROP 2 LAST CDS_LIB pure_quanta_power
J 0
(-3875 2450);
DISPLAY INVISIBLE (-3875 2450);
FORCEPROP 1 LAST PATH I82
J 0
(-3825 2475);
DISPLAY 0.872340 (-3825 2475);
PAINT AQUA (-3825 2475);
DISPLAY INVISIBLE (-3825 2475);
FORCEADD Q_RES..2
(-3875 1525);
FORCEPROP 1 LAST LOCATION R1329
J 0
(-3830 1650);
DISPLAY 0.489362 (-3830 1650);
PAINT SKYBLUE (-3830 1650);
FORCEPROP 0 LAST $SEC 1
J 0
(-3825 1700);
DISPLAY 0.680851 (-3825 1700);
PAINT MONO (-3825 1700);
DISPLAY INVISIBLE (-3825 1700);
FORCEPROP 0 LAST CDS_SEC 1
J 0
(-3825 1700);
DISPLAY 0.680851 (-3825 1700);
DISPLAY INVISIBLE (-3825 1700);
FORCEPROP 1 LASTPIN (-3875 1625) $PN 1
J 0
(-3870 1587);
DISPLAY 0.489362 (-3870 1587);
PAINT MONO (-3870 1587);
FORCEPROP 1 LASTPIN (-3875 1425) $PN 2
J 0
(-3870 1435);
DISPLAY 0.489362 (-3870 1435);
PAINT MONO (-3870 1435);
FORCEPROP 1 LAST WATTAGE 1/16W
J 0
(-3835 1500);
DISPLAY 0.489362 (-3835 1500);
PAINT SKYBLUE (-3835 1500);
FORCEPROP 1 LAST MATERIAL CHIP
J 0
(-3835 1450);
DISPLAY 0.489362 (-3835 1450);
PAINT SKYBLUE (-3835 1450);
FORCEPROP 1 LAST TOLERANCE 1%
J 0
(-3830 1550);
DISPLAY 0.489362 (-3830 1550);
PAINT SKYBLUE (-3830 1550);
FORCEPROP 1 LAST VALUE 4.7K
J 0
(-3830 1600);
DISPLAY 0.489362 (-3830 1600);
PAINT SKYBLUE (-3830 1600);
FORCEPROP 1 LAST PART_NUMBER CS24702FB10
J 0
(-3835 1400);
DISPLAY 0.489362 (-3835 1400);
PAINT SKYBLUE (-3835 1400);
FORCEPROP 1 LAST PACK_TYPE 0402LF
J 0
(-3835 1350);
DISPLAY 0.489362 (-3835 1350);
PAINT SKYBLUE (-3835 1350);
FORCEPROP 2 LAST CDS_LIB pure_quanta
J 0
(-3875 1525);
DISPLAY INVISIBLE (-3875 1525);
FORCEPROP 1 LAST PATH I83
J 0
(-3825 1700);
DISPLAY 0.978723 (-3825 1700);
PAINT WHITE (-3825 1700);
DISPLAY INVISIBLE (-3825 1700);
FORCEADD UNIVERSAL_POWER..1
(-3875 1725);
FORCEPROP 3 LASTPIN (-3875 1675) SIG_NAME P3V3_STBY\g
J 0
(-3865 1685);
DISPLAY 0.659574 (-3865 1685);
PAINT MONO (-3865 1685);
DISPLAY INVISIBLE (-3865 1685);
FORCEPROP 1 LAST HDL_POWER P3V3_STBY
J 1
(-3875 1775);
DISPLAY 0.489362 (-3875 1775);
PAINT GREEN (-3875 1775);
FORCEPROP 2 LAST CDS_LIB pure_quanta_power
J 0
(-3875 1725);
DISPLAY INVISIBLE (-3875 1725);
FORCEPROP 1 LAST PATH I84
J 0
(-3825 1750);
DISPLAY 0.872340 (-3825 1750);
PAINT AQUA (-3825 1750);
DISPLAY INVISIBLE (-3825 1750);
FORCEADD OFFPAGE..2
(-1550 4650);
FORCEPROP 2 LAST $XR0 119 
J 0
(-1361 4650);
DISPLAY 0.638298 (-1361 4650);
PAINT MONO (-1361 4650);
FORCEPROP 2 LAST CDS_LIB standard
J 0
(-1550 4650);
PAINT MONO (-1550 4650);
DISPLAY INVISIBLE (-1550 4650);
FORCEPROP 1 LAST OFFPAGE TRUE
J 0
(-1225 4525);
DISPLAY 0.872340 (-1225 4525);
PAINT GREEN (-1225 4525);
DISPLAY INVISIBLE (-1225 4525);
FORCEPROP 1 LAST COMMENT_BODY TRUE
J 0
(-1595 4555);
DISPLAY 0.872340 (-1595 4555);
PAINT GREEN (-1595 4555);
DISPLAY INVISIBLE (-1595 4555);
FORCEPROP 2 LAST PATH I85
J 0
(-1350 4700);
DISPLAY 0.680851 (-1350 4700);
DISPLAY INVISIBLE (-1350 4700);
FORCEADD Q_RES..1
R 2
(-2725 4650);
FORCEPROP 1 LAST LOCATION R1222
J 0
(-2725 4675);
DISPLAY 0.489362 (-2725 4675);
PAINT SKYBLUE (-2725 4675);
FORCEPROP 0 LAST $SEC 1
J 0
(-2725 4700);
DISPLAY 0.680851 (-2725 4700);
PAINT MONO (-2725 4700);
DISPLAY INVISIBLE (-2725 4700);
FORCEPROP 0 LAST CDS_SEC 1
J 0
(-2725 4700);
DISPLAY 0.680851 (-2725 4700);
DISPLAY INVISIBLE (-2725 4700);
FORCEPROP 1 LASTPIN (-2625 4650) $PN 1
J 2
(-2637 4662);
DISPLAY 0.489362 (-2637 4662);
PAINT MONO (-2637 4662);
FORCEPROP 1 LASTPIN (-2825 4650) $PN 2
J 2
(-2787 4662);
DISPLAY 0.489362 (-2787 4662);
PAINT MONO (-2787 4662);
FORCEPROP 1 LAST VALUE 33
J 0
(-2600 4650);
DISPLAY 0.489362 (-2600 4650);
PAINT SKYBLUE (-2600 4650);
FORCEPROP 2 LAST BOM_COST MEM
J 0
(-2750 4800);
DISPLAY 0.744681 (-2750 4800);
PAINT WHITE (-2750 4800);
DISPLAY INVISIBLE (-2750 4800);
FORCEPROP 2 LAST CDS_LIB pure_quanta
J 0
(-2725 4650);
DISPLAY INVISIBLE (-2725 4650);
FORCEPROP 1 LAST PATH I86
J 2
(-2675 4800);
DISPLAY 0.978723 (-2675 4800);
PAINT WHITE (-2675 4800);
DISPLAY INVISIBLE (-2675 4800);
FORCEPROP 1 LAST WATTAGE 1/16W
J 0
(-2650 4575);
DISPLAY 0.489362 (-2650 4575);
PAINT SKYBLUE (-2650 4575);
DISPLAY INVISIBLE (-2650 4575);
FORCEPROP 1 LAST MATERIAL CHIP
J 0
(-2900 4625);
DISPLAY 0.489362 (-2900 4625);
PAINT SKYBLUE (-2900 4625);
DISPLAY INVISIBLE (-2900 4625);
FORCEPROP 1 LAST TOLERANCE 5%
J 2
(-2600 4625);
DISPLAY 0.489362 (-2600 4625);
PAINT SKYBLUE (-2600 4625);
DISPLAY INVISIBLE (-2600 4625);
FORCEPROP 1 LAST PART_NUMBER CS03302JB29
J 0
(-2825 4700);
DISPLAY 0.489362 (-2825 4700);
PAINT SKYBLUE (-2825 4700);
DISPLAY INVISIBLE (-2825 4700);
FORCEPROP 1 LAST PACK_TYPE 0402LF
J 0
(-2900 4575);
DISPLAY 0.489362 (-2900 4575);
PAINT SKYBLUE (-2900 4575);
DISPLAY INVISIBLE (-2900 4575);
FORCEPROP 2 LAST ROOM RST_CPU0_PLD_TO_DIMM
J 0
(-2750 4750);
DISPLAY 0.744681 (-2750 4750);
PAINT RED (-2750 4750);
DISPLAY INVISIBLE (-2750 4750);
FORCEADD OFFPAGE..2
(-1600 3975);
FORCEPROP 2 LAST $XR1 114 
J 0
(-1321 3975);
DISPLAY 0.638298 (-1321 3975);
PAINT MONO (-1321 3975);
FORCEPROP 2 LAST $XR0 79 
J 0
(-1411 3975);
DISPLAY 0.638298 (-1411 3975);
PAINT MONO (-1411 3975);
FORCEPROP 2 LAST CDS_LIB standard
J 0
(-1600 3975);
PAINT MONO (-1600 3975);
DISPLAY INVISIBLE (-1600 3975);
FORCEPROP 1 LAST OFFPAGE TRUE
J 0
(-1275 3850);
DISPLAY 0.872340 (-1275 3850);
PAINT GREEN (-1275 3850);
DISPLAY INVISIBLE (-1275 3850);
FORCEPROP 1 LAST COMMENT_BODY TRUE
J 0
(-1645 3880);
DISPLAY 0.872340 (-1645 3880);
PAINT GREEN (-1645 3880);
DISPLAY INVISIBLE (-1645 3880);
FORCEPROP 2 LAST PATH I87
J 0
(-1300 4025);
DISPLAY 0.680851 (-1300 4025);
DISPLAY INVISIBLE (-1300 4025);
FORCEADD OFFPAGE..2
(-1500 3300);
FORCEPROP 2 LAST $XR1 114 
J 0
(-1221 3300);
DISPLAY 0.638298 (-1221 3300);
PAINT MONO (-1221 3300);
FORCEPROP 2 LAST $XR0 79 
J 0
(-1311 3300);
DISPLAY 0.638298 (-1311 3300);
PAINT MONO (-1311 3300);
FORCEPROP 2 LAST CDS_LIB standard
J 0
(-1500 3300);
PAINT MONO (-1500 3300);
DISPLAY INVISIBLE (-1500 3300);
FORCEPROP 1 LAST OFFPAGE TRUE
J 0
(-1175 3175);
DISPLAY 0.872340 (-1175 3175);
PAINT GREEN (-1175 3175);
DISPLAY INVISIBLE (-1175 3175);
FORCEPROP 1 LAST COMMENT_BODY TRUE
J 0
(-1545 3205);
DISPLAY 0.872340 (-1545 3205);
PAINT GREEN (-1545 3205);
DISPLAY INVISIBLE (-1545 3205);
FORCEPROP 2 LAST PATH I88
J 0
(-1200 3350);
DISPLAY 0.680851 (-1200 3350);
DISPLAY INVISIBLE (-1200 3350);
FORCEADD OFFPAGE..2
(-1525 2575);
FORCEPROP 2 LAST $XR1 115 
J 0
(-1246 2575);
DISPLAY 0.638298 (-1246 2575);
PAINT MONO (-1246 2575);
FORCEPROP 2 LAST $XR0 79 
J 0
(-1336 2575);
DISPLAY 0.638298 (-1336 2575);
PAINT MONO (-1336 2575);
FORCEPROP 2 LAST CDS_LIB standard
J 0
(-1525 2575);
PAINT MONO (-1525 2575);
DISPLAY INVISIBLE (-1525 2575);
FORCEPROP 1 LAST OFFPAGE TRUE
J 0
(-1200 2450);
DISPLAY 0.872340 (-1200 2450);
PAINT GREEN (-1200 2450);
DISPLAY INVISIBLE (-1200 2450);
FORCEPROP 1 LAST COMMENT_BODY TRUE
J 0
(-1570 2480);
DISPLAY 0.872340 (-1570 2480);
PAINT GREEN (-1570 2480);
DISPLAY INVISIBLE (-1570 2480);
FORCEPROP 2 LAST PATH I89
J 0
(-1225 2625);
DISPLAY 0.680851 (-1225 2625);
DISPLAY INVISIBLE (-1225 2625);
FORCEADD OFFPAGE..2
(-1525 1875);
FORCEPROP 2 LAST $XR1 115 
J 0
(-1246 1875);
DISPLAY 0.638298 (-1246 1875);
PAINT MONO (-1246 1875);
FORCEPROP 2 LAST $XR0 79 
J 0
(-1336 1875);
DISPLAY 0.638298 (-1336 1875);
PAINT MONO (-1336 1875);
FORCEPROP 2 LAST CDS_LIB standard
J 0
(-1525 1875);
PAINT MONO (-1525 1875);
DISPLAY INVISIBLE (-1525 1875);
FORCEPROP 1 LAST OFFPAGE TRUE
J 0
(-1200 1750);
DISPLAY 0.872340 (-1200 1750);
PAINT GREEN (-1200 1750);
DISPLAY INVISIBLE (-1200 1750);
FORCEPROP 1 LAST COMMENT_BODY TRUE
J 0
(-1570 1780);
DISPLAY 0.872340 (-1570 1780);
PAINT GREEN (-1570 1780);
DISPLAY INVISIBLE (-1570 1780);
FORCEPROP 2 LAST PATH I90
J 0
(-1225 1925);
DISPLAY 0.680851 (-1225 1925);
DISPLAY INVISIBLE (-1225 1925);
FORCEADD OFFPAGE..2
(-1525 1150);
FORCEPROP 2 LAST $XR1 116 
J 0
(-1246 1150);
DISPLAY 0.638298 (-1246 1150);
PAINT MONO (-1246 1150);
FORCEPROP 2 LAST $XR0 79 
J 0
(-1336 1150);
DISPLAY 0.638298 (-1336 1150);
PAINT MONO (-1336 1150);
FORCEPROP 2 LAST CDS_LIB standard
J 0
(-1525 1150);
PAINT MONO (-1525 1150);
DISPLAY INVISIBLE (-1525 1150);
FORCEPROP 1 LAST OFFPAGE TRUE
J 0
(-1200 1025);
DISPLAY 0.872340 (-1200 1025);
PAINT GREEN (-1200 1025);
DISPLAY INVISIBLE (-1200 1025);
FORCEPROP 1 LAST COMMENT_BODY TRUE
J 0
(-1570 1055);
DISPLAY 0.872340 (-1570 1055);
PAINT GREEN (-1570 1055);
DISPLAY INVISIBLE (-1570 1055);
FORCEPROP 2 LAST PATH I91
J 0
(-1225 1200);
DISPLAY 0.680851 (-1225 1200);
DISPLAY INVISIBLE (-1225 1200);
FORCEADD Q_RES..1
R 2
(-2725 3975);
FORCEPROP 1 LAST LOCATION R1223
J 2
(-2675 4025);
DISPLAY 0.489362 (-2675 4025);
PAINT SKYBLUE (-2675 4025);
FORCEPROP 0 LAST $SEC 1
J 0
(-2675 4075);
DISPLAY 0.680851 (-2675 4075);
PAINT MONO (-2675 4075);
DISPLAY INVISIBLE (-2675 4075);
FORCEPROP 0 LAST CDS_SEC 1
J 0
(-2675 4075);
DISPLAY 0.680851 (-2675 4075);
DISPLAY INVISIBLE (-2675 4075);
FORCEPROP 1 LASTPIN (-2625 3975) $PN 1
J 2
(-2637 3987);
DISPLAY 0.489362 (-2637 3987);
PAINT MONO (-2637 3987);
FORCEPROP 1 LASTPIN (-2825 3975) $PN 2
J 2
(-2787 3987);
DISPLAY 0.489362 (-2787 3987);
PAINT MONO (-2787 3987);
FORCEPROP 1 LAST VALUE 33
J 0
(-2600 3975);
DISPLAY 0.489362 (-2600 3975);
PAINT SKYBLUE (-2600 3975);
FORCEPROP 2 LAST CDS_LIB pure_quanta
J 0
(-2725 3975);
DISPLAY INVISIBLE (-2725 3975);
FORCEPROP 2 LAST BOM_COST MEM
J 0
(-2750 4125);
DISPLAY 0.744681 (-2750 4125);
PAINT WHITE (-2750 4125);
DISPLAY INVISIBLE (-2750 4125);
FORCEPROP 1 LAST PATH I92
J 2
(-2675 4125);
DISPLAY 0.978723 (-2675 4125);
PAINT WHITE (-2675 4125);
DISPLAY INVISIBLE (-2675 4125);
FORCEPROP 1 LAST WATTAGE 1/16W
J 0
(-2650 3900);
DISPLAY 0.489362 (-2650 3900);
PAINT SKYBLUE (-2650 3900);
DISPLAY INVISIBLE (-2650 3900);
FORCEPROP 1 LAST MATERIAL CHIP
J 0
(-2900 3950);
DISPLAY 0.489362 (-2900 3950);
PAINT SKYBLUE (-2900 3950);
DISPLAY INVISIBLE (-2900 3950);
FORCEPROP 1 LAST TOLERANCE 5%
J 2
(-2600 3950);
DISPLAY 0.489362 (-2600 3950);
PAINT SKYBLUE (-2600 3950);
DISPLAY INVISIBLE (-2600 3950);
FORCEPROP 1 LAST PART_NUMBER CS03302JB29
J 0
(-2825 4025);
DISPLAY 0.489362 (-2825 4025);
PAINT SKYBLUE (-2825 4025);
DISPLAY INVISIBLE (-2825 4025);
FORCEPROP 1 LAST PACK_TYPE 0402LF
J 0
(-2900 3900);
DISPLAY 0.489362 (-2900 3900);
PAINT SKYBLUE (-2900 3900);
DISPLAY INVISIBLE (-2900 3900);
FORCEPROP 2 LAST ROOM RST_CPU0_PLD_TO_DIMM
J 0
(-2750 4075);
DISPLAY 0.744681 (-2750 4075);
PAINT RED (-2750 4075);
DISPLAY INVISIBLE (-2750 4075);
FORCEADD Q_RES..1
R 2
(-2725 3300);
FORCEPROP 1 LAST LOCATION R1224
J 2
(-2675 3350);
DISPLAY 0.489362 (-2675 3350);
PAINT SKYBLUE (-2675 3350);
FORCEPROP 0 LAST $SEC 1
J 0
(-2675 3400);
DISPLAY 0.680851 (-2675 3400);
PAINT MONO (-2675 3400);
DISPLAY INVISIBLE (-2675 3400);
FORCEPROP 0 LAST CDS_SEC 1
J 0
(-2675 3400);
DISPLAY 0.680851 (-2675 3400);
DISPLAY INVISIBLE (-2675 3400);
FORCEPROP 1 LASTPIN (-2625 3300) $PN 1
J 2
(-2637 3312);
DISPLAY 0.489362 (-2637 3312);
PAINT MONO (-2637 3312);
FORCEPROP 1 LASTPIN (-2825 3300) $PN 2
J 2
(-2787 3312);
DISPLAY 0.489362 (-2787 3312);
PAINT MONO (-2787 3312);
FORCEPROP 1 LAST VALUE 33
J 0
(-2600 3300);
DISPLAY 0.489362 (-2600 3300);
PAINT SKYBLUE (-2600 3300);
FORCEPROP 2 LAST CDS_LIB pure_quanta
J 0
(-2725 3300);
DISPLAY INVISIBLE (-2725 3300);
FORCEPROP 2 LAST BOM_COST MEM
J 0
(-2750 3450);
DISPLAY 0.744681 (-2750 3450);
PAINT WHITE (-2750 3450);
DISPLAY INVISIBLE (-2750 3450);
FORCEPROP 1 LAST PATH I93
J 2
(-2675 3450);
DISPLAY 0.978723 (-2675 3450);
PAINT WHITE (-2675 3450);
DISPLAY INVISIBLE (-2675 3450);
FORCEPROP 1 LAST WATTAGE 1/16W
J 0
(-2650 3225);
DISPLAY 0.489362 (-2650 3225);
PAINT SKYBLUE (-2650 3225);
DISPLAY INVISIBLE (-2650 3225);
FORCEPROP 1 LAST MATERIAL CHIP
J 0
(-2900 3275);
DISPLAY 0.489362 (-2900 3275);
PAINT SKYBLUE (-2900 3275);
DISPLAY INVISIBLE (-2900 3275);
FORCEPROP 1 LAST TOLERANCE 5%
J 2
(-2600 3275);
DISPLAY 0.489362 (-2600 3275);
PAINT SKYBLUE (-2600 3275);
DISPLAY INVISIBLE (-2600 3275);
FORCEPROP 1 LAST PART_NUMBER CS03302JB29
J 0
(-2825 3350);
DISPLAY 0.489362 (-2825 3350);
PAINT SKYBLUE (-2825 3350);
DISPLAY INVISIBLE (-2825 3350);
FORCEPROP 1 LAST PACK_TYPE 0402LF
J 0
(-2900 3225);
DISPLAY 0.489362 (-2900 3225);
PAINT SKYBLUE (-2900 3225);
DISPLAY INVISIBLE (-2900 3225);
FORCEPROP 2 LAST ROOM RST_CPU0_PLD_TO_DIMM
J 0
(-2750 3400);
DISPLAY 0.744681 (-2750 3400);
PAINT RED (-2750 3400);
DISPLAY INVISIBLE (-2750 3400);
FORCEADD Q_RES..1
R 2
(-2725 2575);
FORCEPROP 1 LAST LOCATION R1231
J 2
(-2675 2625);
DISPLAY 0.489362 (-2675 2625);
PAINT SKYBLUE (-2675 2625);
FORCEPROP 0 LAST $SEC 1
J 0
(-2675 2675);
DISPLAY 0.680851 (-2675 2675);
PAINT MONO (-2675 2675);
DISPLAY INVISIBLE (-2675 2675);
FORCEPROP 0 LAST CDS_SEC 1
J 0
(-2675 2675);
DISPLAY 0.680851 (-2675 2675);
DISPLAY INVISIBLE (-2675 2675);
FORCEPROP 1 LASTPIN (-2625 2575) $PN 1
J 2
(-2637 2587);
DISPLAY 0.489362 (-2637 2587);
PAINT MONO (-2637 2587);
FORCEPROP 1 LASTPIN (-2825 2575) $PN 2
J 2
(-2787 2587);
DISPLAY 0.489362 (-2787 2587);
PAINT MONO (-2787 2587);
FORCEPROP 1 LAST VALUE 33
J 0
(-2600 2575);
DISPLAY 0.489362 (-2600 2575);
PAINT SKYBLUE (-2600 2575);
FORCEPROP 2 LAST BOM_COST MEM
J 0
(-2750 2725);
DISPLAY 0.744681 (-2750 2725);
PAINT WHITE (-2750 2725);
DISPLAY INVISIBLE (-2750 2725);
FORCEPROP 2 LAST CDS_LIB pure_quanta
J 0
(-2725 2575);
DISPLAY INVISIBLE (-2725 2575);
FORCEPROP 1 LAST PATH I94
J 2
(-2675 2725);
DISPLAY 0.978723 (-2675 2725);
PAINT WHITE (-2675 2725);
DISPLAY INVISIBLE (-2675 2725);
FORCEPROP 1 LAST WATTAGE 1/16W
J 0
(-2650 2500);
DISPLAY 0.489362 (-2650 2500);
PAINT SKYBLUE (-2650 2500);
DISPLAY INVISIBLE (-2650 2500);
FORCEPROP 1 LAST MATERIAL CHIP
J 0
(-2900 2550);
DISPLAY 0.489362 (-2900 2550);
PAINT SKYBLUE (-2900 2550);
DISPLAY INVISIBLE (-2900 2550);
FORCEPROP 1 LAST TOLERANCE 5%
J 2
(-2600 2550);
DISPLAY 0.489362 (-2600 2550);
PAINT SKYBLUE (-2600 2550);
DISPLAY INVISIBLE (-2600 2550);
FORCEPROP 1 LAST PART_NUMBER CS03302JB29
J 0
(-2825 2625);
DISPLAY 0.489362 (-2825 2625);
PAINT SKYBLUE (-2825 2625);
DISPLAY INVISIBLE (-2825 2625);
FORCEPROP 1 LAST PACK_TYPE 0402LF
J 0
(-2900 2500);
DISPLAY 0.489362 (-2900 2500);
PAINT SKYBLUE (-2900 2500);
DISPLAY INVISIBLE (-2900 2500);
FORCEPROP 2 LAST ROOM RST_CPU0_PLD_TO_DIMM
J 0
(-2750 2675);
DISPLAY 0.744681 (-2750 2675);
PAINT RED (-2750 2675);
DISPLAY INVISIBLE (-2750 2675);
FORCEADD Q_RES..1
R 2
(-2725 1875);
FORCEPROP 1 LAST LOCATION R1243
J 2
(-2675 1925);
DISPLAY 0.489362 (-2675 1925);
PAINT SKYBLUE (-2675 1925);
FORCEPROP 0 LAST $SEC 1
J 0
(-2675 1975);
DISPLAY 0.680851 (-2675 1975);
PAINT MONO (-2675 1975);
DISPLAY INVISIBLE (-2675 1975);
FORCEPROP 0 LAST CDS_SEC 1
J 0
(-2675 1975);
DISPLAY 0.680851 (-2675 1975);
DISPLAY INVISIBLE (-2675 1975);
FORCEPROP 1 LASTPIN (-2625 1875) $PN 1
J 2
(-2637 1887);
DISPLAY 0.489362 (-2637 1887);
PAINT MONO (-2637 1887);
FORCEPROP 1 LASTPIN (-2825 1875) $PN 2
J 2
(-2787 1887);
DISPLAY 0.489362 (-2787 1887);
PAINT MONO (-2787 1887);
FORCEPROP 1 LAST VALUE 33
J 0
(-2600 1875);
DISPLAY 0.489362 (-2600 1875);
PAINT SKYBLUE (-2600 1875);
FORCEPROP 2 LAST BOM_COST MEM
J 0
(-2750 2025);
DISPLAY 0.744681 (-2750 2025);
PAINT WHITE (-2750 2025);
DISPLAY INVISIBLE (-2750 2025);
FORCEPROP 2 LAST CDS_LIB pure_quanta
J 0
(-2725 1875);
DISPLAY INVISIBLE (-2725 1875);
FORCEPROP 1 LAST PATH I95
J 2
(-2675 2025);
DISPLAY 0.978723 (-2675 2025);
PAINT WHITE (-2675 2025);
DISPLAY INVISIBLE (-2675 2025);
FORCEPROP 1 LAST WATTAGE 1/16W
J 0
(-2650 1800);
DISPLAY 0.489362 (-2650 1800);
PAINT SKYBLUE (-2650 1800);
DISPLAY INVISIBLE (-2650 1800);
FORCEPROP 1 LAST MATERIAL CHIP
J 0
(-2900 1850);
DISPLAY 0.489362 (-2900 1850);
PAINT SKYBLUE (-2900 1850);
DISPLAY INVISIBLE (-2900 1850);
FORCEPROP 1 LAST TOLERANCE 5%
J 2
(-2600 1850);
DISPLAY 0.489362 (-2600 1850);
PAINT SKYBLUE (-2600 1850);
DISPLAY INVISIBLE (-2600 1850);
FORCEPROP 1 LAST PART_NUMBER CS03302JB29
J 0
(-2825 1925);
DISPLAY 0.489362 (-2825 1925);
PAINT SKYBLUE (-2825 1925);
DISPLAY INVISIBLE (-2825 1925);
FORCEPROP 1 LAST PACK_TYPE 0402LF
J 0
(-2900 1800);
DISPLAY 0.489362 (-2900 1800);
PAINT SKYBLUE (-2900 1800);
DISPLAY INVISIBLE (-2900 1800);
FORCEPROP 2 LAST ROOM RST_CPU0_PLD_TO_DIMM
J 0
(-2750 1975);
DISPLAY 0.744681 (-2750 1975);
PAINT RED (-2750 1975);
DISPLAY INVISIBLE (-2750 1975);
FORCEADD Q_RES..1
R 2
(-2725 1150);
FORCEPROP 1 LAST LOCATION R1244
J 2
(-2675 1200);
DISPLAY 0.489362 (-2675 1200);
PAINT SKYBLUE (-2675 1200);
FORCEPROP 0 LAST $SEC 1
J 0
(-2675 1250);
DISPLAY 0.680851 (-2675 1250);
PAINT MONO (-2675 1250);
DISPLAY INVISIBLE (-2675 1250);
FORCEPROP 0 LAST CDS_SEC 1
J 0
(-2675 1250);
DISPLAY 0.680851 (-2675 1250);
DISPLAY INVISIBLE (-2675 1250);
FORCEPROP 1 LASTPIN (-2625 1150) $PN 1
J 2
(-2637 1162);
DISPLAY 0.489362 (-2637 1162);
PAINT MONO (-2637 1162);
FORCEPROP 1 LASTPIN (-2825 1150) $PN 2
J 2
(-2787 1162);
DISPLAY 0.489362 (-2787 1162);
PAINT MONO (-2787 1162);
FORCEPROP 1 LAST VALUE 33
J 0
(-2600 1150);
DISPLAY 0.489362 (-2600 1150);
PAINT SKYBLUE (-2600 1150);
FORCEPROP 2 LAST BOM_COST MEM
J 0
(-2750 1300);
DISPLAY 0.744681 (-2750 1300);
PAINT WHITE (-2750 1300);
DISPLAY INVISIBLE (-2750 1300);
FORCEPROP 2 LAST CDS_LIB pure_quanta
J 0
(-2725 1150);
DISPLAY INVISIBLE (-2725 1150);
FORCEPROP 1 LAST PATH I96
J 2
(-2675 1300);
DISPLAY 0.978723 (-2675 1300);
PAINT WHITE (-2675 1300);
DISPLAY INVISIBLE (-2675 1300);
FORCEPROP 1 LAST WATTAGE 1/16W
J 0
(-2650 1075);
DISPLAY 0.489362 (-2650 1075);
PAINT SKYBLUE (-2650 1075);
DISPLAY INVISIBLE (-2650 1075);
FORCEPROP 1 LAST MATERIAL CHIP
J 0
(-2900 1125);
DISPLAY 0.489362 (-2900 1125);
PAINT SKYBLUE (-2900 1125);
DISPLAY INVISIBLE (-2900 1125);
FORCEPROP 1 LAST TOLERANCE 5%
J 2
(-2600 1125);
DISPLAY 0.489362 (-2600 1125);
PAINT SKYBLUE (-2600 1125);
DISPLAY INVISIBLE (-2600 1125);
FORCEPROP 1 LAST PART_NUMBER CS03302JB29
J 0
(-2825 1200);
DISPLAY 0.489362 (-2825 1200);
PAINT SKYBLUE (-2825 1200);
DISPLAY INVISIBLE (-2825 1200);
FORCEPROP 1 LAST PACK_TYPE 0402LF
J 0
(-2900 1075);
DISPLAY 0.489362 (-2900 1075);
PAINT SKYBLUE (-2900 1075);
DISPLAY INVISIBLE (-2900 1075);
FORCEPROP 2 LAST ROOM RST_CPU0_PLD_TO_DIMM
J 0
(-2750 1250);
DISPLAY 0.744681 (-2750 1250);
PAINT RED (-2750 1250);
DISPLAY INVISIBLE (-2750 1250);
FORCEADD QUANTA_TITLE_BLOCK_C..1
(0 0);
FORCEPROP 0 LAST CDS_CON_LAST_MODIFIED Fri Mar 11 14:53:12 2022
J 0
(-1885 15);
DISPLAY INVISIBLE (-1885 15);
FORCEPROP 1 LAST CUSTOM_TXT_CDS <CON_LAST_MODIFIED>
J 0
(-1885 15);
DISPLAY 0.978723 (-1885 15);
FORCEPROP 2 LAST CUSTOM_TXT_CDS <XR_PAGE_TITLE>
J 0
(-7890 5250);
DISPLAY 0.638298 (-7890 5250);
PAINT PINK (-7890 5250);
DISPLAY INVISIBLE (-7890 5250);
FORCEPROP 1 LAST CUSTOM_TXT_CDS <NAME_2>
J 0
(-3175 50);
FORCEPROP 1 LAST CUSTOM_TXT_CDS <NAME_1>
J 0
(-3175 175);
FORCEPROP 1 LAST CUSTOM_TXT_CDS <Q_NUMBER>
J 0
(-1403 103);
DISPLAY 1.212766 (-1403 103);
FORCEPROP 1 LAST CUSTOM_TXT_CDS <Q_PROJ>
J 0
(-2382 102);
DISPLAY 1.212766 (-2382 102);
FORCEPROP 1 LAST CUSTOM_TXT_CDS <Q_REV>
J 0
(-184 103);
DISPLAY 1.212766 (-184 103);
FORCEPROP 1 LAST CUSTOM_TXT_CDS <CON_PAGE_NUM> OF <CON_TOTAL_PAGES>
J 0
(-446 18);
DISPLAY 0.978723 (-446 18);
FORCEPROP 1 LAST Q_TITLE SYSTEM THROTTLE
J 0
(-9300 75);
DISPLAY 2.446809 (-9300 75);
PAINT GREEN (-9300 75);
FORCEPROP 1 LAST Q_DEPT BU9
J 1
(-3763 49);
DISPLAY 1.957447 (-3763 49);
PAINT GREEN (-3763 49);
FORCEPROP 2 LAST CDS_LIB pure_quanta
J 0
(0 0);
DISPLAY INVISIBLE (0 0);
FORCEPROP 1 LAST CDS_LMAN_SYM_OUTLINE -9475,6775,100,-125
J 0
(0 0);
DISPLAY 0.468085 (0 0);
PAINT GREEN (0 0);
DISPLAY INVISIBLE (0 0);
FORCEPROP 2 LAST PAGE_BORDER TRUE
J 0
(-7890 5250);
DISPLAY 0.638298 (-7890 5250);
PAINT PINK (-7890 5250);
DISPLAY INVISIBLE (-7890 5250);
FORCEPROP 1 LAST COMMENT_BODY TRUE
J 0
(12 -13);
DISPLAY 0.978723 (12 -13);
PAINT GREEN (12 -13);
DISPLAY INVISIBLE (12 -13);
FORCEPROP 2 LAST CDS_XR_PAGE_TITLE CR-133 : @T6G_MB_LIB.T6G(SCH_1):PAGE133
J 0
(-7890 5250);
DISPLAY 0.638298 (-7890 5250);
PAINT PINK (-7890 5250);
DISPLAY INVISIBLE (-7890 5250);
WIRE 16 -1 (-3925 5125)(-3925 5175);
WIRE 16 -1 (-3925 4450)(-3925 4500);
WIRE 16 -1 (-7325 4850)(-7325 4800);
WIRE 16 -1 (-4725 5125)(-4725 5175);
WIRE 16 -1 (-3900 3775)(-3900 3825);
WIRE 16 -1 (-3875 3050)(-3875 3100);
WIRE 16 -1 (-3875 2350)(-3875 2400);
WIRE 16 -1 (-3875 1625)(-3875 1675);
WIRE 16 -1 (-4725 1150)(-4450 1150);
WIRE 16 -1 (-4725 1150)(-4725 1875);
WIRE 16 -1 (-4725 1875)(-4725 2575);
WIRE 16 -1 (-4725 1875)(-4450 1875);
WIRE 16 -1 (-4725 2575)(-4725 3300);
WIRE 16 -1 (-4725 2575)(-4425 2575);
WIRE 16 -1 (-4725 3300)(-4400 3300);
WIRE 16 -1 (-4725 3300)(-4725 3975);
WIRE 16 -1 (-4725 4650)(-4725 3975);
WIRE 16 -1 (-4725 3975)(-4425 3975);
WIRE 16 -1 (-4725 4650)(-4450 4650);
WIRE 16 -1 (-4725 4925)(-4725 4650);
WIRE 16 -1 (-5775 4650)(-4725 4650);
FORCEPROP 0 LAST SIG_NAME FM_SYS_THROTTLE_BUF_R_N
J 0
(-5485 4685);
DISPLAY 0.489362 (-5485 4685);
FORCEPROP 2 LASTPROP $XRERR UNIQUE?
J 0
(-5725 4685);
DISPLAY 0.638298 (-5725 4685);
PAINT MONO (-5725 4685);
DISPLAY INVISIBLE (-5725 4685);
WIRE 16 -1 (-7325 5050)(-7325 5125);
WIRE 16 -1 (-7325 5125)(-7250 5125);
WIRE 16 -1 (-7250 5175)(-7250 5125);
WIRE 16 -1 (-7250 5125)(-7250 4750);
WIRE 16 -1 (-7250 4750)(-7150 4750);
WIRE 16 -1 (-7225 4475)(-7225 4550);
WIRE 16 -1 (-7225 4550)(-7150 4550);
WIRE 16 -1 (-7150 4650)(-8050 4650);
FORCEPROP 0 LAST CDS_PHYS_NET_NAME FM_SYS_THROTTLE_R_N
J 0
(-8025 4692);
PAINT MONO (-8025 4692);
DISPLAY INVISIBLE (-8025 4692);
FORCEPROP 0 LAST SIG_NAME FM_SYS_THROTTLE_N
J 0
(-7825 4660);
DISPLAY 0.489362 (-7825 4660);
WIRE 16 -1 (-5975 4650)(-6800 4650);
FORCEPROP 0 LAST SIG_NAME FM_SYS_THROTTLE_BUF_N
J 0
(-6650 4660);
DISPLAY 0.489362 (-6650 4660);
FORCEPROP 2 LASTPROP $XRERR UNIQUE?
J 0
(-6890 4660);
DISPLAY 0.638298 (-6890 4660);
PAINT MONO (-6890 4660);
DISPLAY INVISIBLE (-6890 4660);
WIRE 16 -1 (-4200 1150)(-3875 1150);
FORCEPROP 0 LAST CDS_PHYS_NET_NAME FM_SYS_PWRBRK_LVC3_GENZ2_0_N
J 0
(-4085 1192);
PAINT MONO (-4085 1192);
DISPLAY INVISIBLE (-4085 1192);
WIRE 16 -1 (-3875 1150)(-2825 1150);
FORCEPROP 2 LAST SIG_NAME FM_SLOT3_PWRBRK_R1_N
J 0
(-3475 1160);
DISPLAY 0.489362 (-3475 1160);
FORCEPROP 2 LASTPROP $XRERR UNIQUE?
J 0
(-3715 1160);
DISPLAY 0.638298 (-3715 1160);
PAINT MONO (-3715 1160);
DISPLAY INVISIBLE (-3715 1160);
WIRE 16 -1 (-3875 1425)(-3875 1150);
WIRE 16 -1 (-4200 1875)(-3875 1875);
FORCEPROP 0 LAST CDS_PHYS_NET_NAME FM_SYS_PWRBRK_LVC3_GENZ1_2_N
J 0
(-4085 1917);
PAINT MONO (-4085 1917);
DISPLAY INVISIBLE (-4085 1917);
WIRE 16 -1 (-3875 2150)(-3875 1875);
WIRE 16 -1 (-3875 1875)(-2825 1875);
FORCEPROP 2 LAST SIG_NAME FM_SLOT2_PWRBRK1_R1_N
J 0
(-3475 1885);
DISPLAY 0.489362 (-3475 1885);
FORCEPROP 2 LASTPROP $XRERR UNIQUE?
J 0
(-3715 1885);
DISPLAY 0.638298 (-3715 1885);
PAINT MONO (-3715 1885);
DISPLAY INVISIBLE (-3715 1885);
WIRE 16 -1 (-4175 2575)(-3875 2575);
FORCEPROP 0 LAST CDS_PHYS_NET_NAME FM_SYS_PWRBRK_LVC3_GENZ1_1_N
J 0
(-4010 2617);
PAINT MONO (-4010 2617);
DISPLAY INVISIBLE (-4010 2617);
WIRE 16 -1 (-3875 2575)(-2825 2575);
FORCEPROP 2 LAST SIG_NAME FM_SLOT2_PWRBRK0_R1_N
J 0
(-3475 2585);
DISPLAY 0.489362 (-3475 2585);
FORCEPROP 2 LASTPROP $XRERR UNIQUE?
J 0
(-3715 2585);
DISPLAY 0.638298 (-3715 2585);
PAINT MONO (-3715 2585);
DISPLAY INVISIBLE (-3715 2585);
WIRE 16 -1 (-3875 2850)(-3875 2575);
WIRE 16 -1 (-4150 3300)(-3900 3300);
FORCEPROP 0 LAST CDS_PHYS_NET_NAME FM_SYS_PWRBRK_LVC3_GENZ1_0_N
J 0
(-3985 3342);
PAINT MONO (-3985 3342);
DISPLAY INVISIBLE (-3985 3342);
WIRE 16 -1 (-3900 3300)(-2825 3300);
FORCEPROP 2 LAST SIG_NAME FM_SLOT1_PWRBRK1_R1_N
J 0
(-3475 3310);
DISPLAY 0.489362 (-3475 3310);
FORCEPROP 2 LASTPROP $XRERR UNIQUE?
J 0
(-3715 3310);
DISPLAY 0.638298 (-3715 3310);
PAINT MONO (-3715 3310);
DISPLAY INVISIBLE (-3715 3310);
WIRE 16 -1 (-3900 3575)(-3900 3300);
WIRE 16 -1 (-1650 3975)(-2625 3975);
FORCEPROP 2 LAST SIG_NAME FM_SLOT1_PWRBRK0_N
J 0
(-2260 4010);
DISPLAY 0.489362 (-2260 4010);
WIRE 16 -1 (-2625 3300)(-1550 3300);
FORCEPROP 2 LAST SIG_NAME FM_SLOT1_PWRBRK1_N
J 0
(-2260 3335);
DISPLAY 0.489362 (-2260 3335);
WIRE 16 -1 (-1575 2575)(-2625 2575);
FORCEPROP 2 LAST SIG_NAME FM_SLOT2_PWRBRK0_N
J 0
(-2260 2610);
DISPLAY 0.489362 (-2260 2610);
WIRE 16 -1 (-2625 1875)(-1575 1875);
FORCEPROP 2 LAST SIG_NAME FM_SLOT2_PWRBRK1_N
J 0
(-2260 1910);
DISPLAY 0.489362 (-2260 1910);
WIRE 16 -1 (-2625 1150)(-1575 1150);
FORCEPROP 2 LAST SIG_NAME FM_SLOT3_PWRBRK_N
J 0
(-2260 1185);
DISPLAY 0.489362 (-2260 1185);
WIRE 16 -1 (-4175 3975)(-3925 3975);
FORCEPROP 0 LAST CDS_PHYS_NET_NAME OCP2_PWRBRK_N
J 0
(-3960 4017);
PAINT MONO (-3960 4017);
DISPLAY INVISIBLE (-3960 4017);
WIRE 16 -1 (-3925 4250)(-3925 3975);
WIRE 16 -1 (-2825 3975)(-3925 3975);
FORCEPROP 2 LAST SIG_NAME FM_SLOT1_PWRBRK0_R1_N
J 0
(-3475 3985);
DISPLAY 0.489362 (-3475 3985);
FORCEPROP 2 LASTPROP $XRERR UNIQUE?
J 0
(-3715 3985);
DISPLAY 0.638298 (-3715 3985);
PAINT MONO (-3715 3985);
DISPLAY INVISIBLE (-3715 3985);
WIRE 16 -1 (-4200 4650)(-3925 4650);
FORCEPROP 0 LAST CDS_PHYS_NET_NAME OCP_PWRBRK_N
J 0
(-3985 4692);
PAINT MONO (-3985 4692);
DISPLAY INVISIBLE (-3985 4692);
WIRE 16 -1 (-2825 4650)(-3925 4650);
FORCEPROP 2 LAST SIG_NAME OCP_PWRBRK_R1_N
J 0
(-3475 4685);
DISPLAY 0.489362 (-3475 4685);
FORCEPROP 2 LASTPROP $XRERR UNIQUE?
J 0
(-3715 4685);
DISPLAY 0.638298 (-3715 4685);
PAINT MONO (-3715 4685);
DISPLAY INVISIBLE (-3715 4685);
WIRE 16 -1 (-3925 4925)(-3925 4650);
WIRE 16 -1 (-1600 4650)(-2625 4650);
FORCEPROP 2 LAST SIG_NAME OCP_PWRBRK_N
J 0
(-2260 4710);
DISPLAY 0.489362 (-2260 4710);
DOT 1 (-3875 1150);
DOT 1 (-3875 1875);
DOT 1 (-3900 3300);
DOT 1 (-3925 3975);
DOT 1 (-3925 4650);
DOT 1 (-7250 5125);
DOT 1 (-4725 4650);
DOT 1 (-4725 3975);
DOT 1 (-4725 3300);
DOT 1 (-4725 2575);
DOT 1 (-4725 1875);
DOT 1 (-3875 2575);
QUIT
